(kicad_pcb
	(version 20241229)
	(generator "pcbnew")
	(generator_version "9.0")
	(general
		(thickness 1.6296)
		(legacy_teardrops no)
	)
	(paper "A3")
	(title_block
		(title "Thunderbolt to 10GbE adapter")
		(date "2026-04-21")
		(rev "1.1.0")
		(company "Antmicro Ltd")
		(comment 1 "www.antmicro.com")
		(comment 9 "footprints 196-200 of 703")
	)
	(layers
		(0 "F.Cu" signal)
		(4 "In1.Cu" signal)
		(6 "In2.Cu" signal)
		(8 "In3.Cu" signal)
		(10 "In4.Cu" signal)
		(12 "In5.Cu" signal)
		(14 "In6.Cu" signal)
		(2 "B.Cu" signal)
		(9 "F.Adhes" user "F.Adhesive")
		(11 "B.Adhes" user "B.Adhesive")
		(13 "F.Paste" user)
		(15 "B.Paste" user)
		(5 "F.SilkS" user "F.Silkscreen")
		(7 "B.SilkS" user "B.Silkscreen")
		(1 "F.Mask" user)
		(3 "B.Mask" user)
		(17 "Dwgs.User" user "User.Drawings")
		(19 "Cmts.User" user "User.Comments")
		(21 "Eco1.User" user "User.Eco1")
		(23 "Eco2.User" user "User.Eco2")
		(25 "Edge.Cuts" user)
		(27 "Margin" user)
		(31 "F.CrtYd" user "F.Courtyard")
		(29 "B.CrtYd" user "B.Courtyard")
		(35 "F.Fab" user)
		(33 "B.Fab" user)
	)
	(footprint "antmicro-footprints:FB_0805_2012Metric"
		(layer "F.Cu")
		(at 122.65 108.9 -90)
		(descr "FERRITE BEAD 0805")
		(tags "FERRITE BEAD 0805")
		(property "Reference" "FB2"
			(at 5.7 -5.35 270)
			(layer "F.SilkS")
			(effects
				(font
					(size 0.7 0.7)
					(thickness 0.15)
				)
			)
		)
		(property "Value" "FB_30Z_8.5A_Murata-BLM21SN_0805"
			(at 0.001 1.801 270)
			(layer "F.Fab")
			(effects
				(font
					(size 0.7 0.7)
					(thickness 0.15)
				)
				(justify left bottom)
			)
		)
		(property "Datasheet" "https://www.murata.com/en-sg/products/productdata/8796738977822/ENFA0005.pdf?1519270210000"
			(at 0 0 270)
			(layer "F.Fab")
			(hide yes)
			(effects
				(font
					(size 1.27 1.27)
					(thickness 0.15)
				)
			)
		)
		(property "Description" "Ferrite Bead, 0805 [2012 Metric], 30 ohm, 8.5 A, BLM21SN, 0.004 ohm, ± 10ohm, DC power line"
			(at 0 0 270)
			(layer "F.Fab")
			(hide yes)
			(effects
				(font
					(size 1.27 1.27)
					(thickness 0.15)
				)
			)
		)
		(property "MPN" "BLM21SN300SZ1D"
			(at 0 0 270)
			(unlocked yes)
			(layer "F.Fab")
			(hide yes)
			(effects
				(font
					(size 1 1)
					(thickness 0.15)
				)
			)
		)
		(property "Manufacturer" "Murata"
			(at 0 0 270)
			(unlocked yes)
			(layer "F.Fab")
			(hide yes)
			(effects
				(font
					(size 1 1)
					(thickness 0.15)
				)
			)
		)
		(property "License" "Apache-2.0"
			(at 0 0 270)
			(unlocked yes)
			(layer "F.Fab")
			(hide yes)
			(effects
				(font
					(size 1 1)
					(thickness 0.15)
				)
			)
		)
		(property "Author" "Antmicro"
			(at 0 0 270)
			(unlocked yes)
			(layer "F.Fab")
			(hide yes)
			(effects
				(font
					(size 1 1)
					(thickness 0.15)
				)
			)
		)
		(property "Val" "30Z/8.5A"
			(at 0 0 270)
			(unlocked yes)
			(layer "F.Fab")
			(hide yes)
			(effects
				(font
					(size 1 1)
					(thickness 0.15)
				)
			)
		)
		(property "Current" ""
			(at 0 0 270)
			(unlocked yes)
			(layer "F.Fab")
			(hide yes)
			(effects
				(font
					(size 1 1)
					(thickness 0.15)
				)
			)
		)
		(sheetname "/PD and TB DC-DC/")
		(sheetfile "PD_and_TB_DC_DC.kicad_sch")
		(attr smd)
		(fp_line
			(start -0.319 0.698)
			(end 0.281 0.698)
			(stroke
				(width 0.15)
				(type solid)
			)
			(layer "F.SilkS")
		)
		(fp_line
			(start -0.299 -0.698)
			(end 0.299 -0.698)
			(stroke
				(width 0.15)
				(type solid)
			)
			(layer "F.SilkS")
		)
		(fp_rect
			(start 1.95 -0.9)
			(end -1.95 0.9)
			(stroke
				(width 0.05)
				(type default)
			)
			(fill no)
			(layer "F.CrtYd")
		)
		(fp_line
			(start -0.948 0.681)
			(end 0.948 0.681)
			(stroke
				(width 0.15)
				(type solid)
			)
			(layer "F.Fab")
		)
		(fp_line
			(start -0.948 -0.676)
			(end -0.948 0.676)
			(stroke
				(width 0.15)
				(type solid)
			)
			(layer "F.Fab")
		)
		(fp_line
			(start 0.948 -0.676)
			(end 0.948 0.676)
			(stroke
				(width 0.15)
				(type solid)
			)
			(layer "F.Fab")
		)
		(fp_line
			(start -0.948 -0.681)
			(end 0.948 -0.681)
			(stroke
				(width 0.15)
				(type solid)
			)
			(layer "F.Fab")
		)
		(fp_text user "License: Apache-2.0"
			(at -1.44 6.201 270)
			(layer "F.Fab")
			(effects
				(font
					(size 0.7 0.7)
					(thickness 0.15)
				)
				(justify left bottom)
			)
		)
		(fp_text user "${REFERENCE}"
			(at -1.44 3.801 270)
			(layer "F.Fab")
			(effects
				(font
					(size 0.7 0.7)
					(thickness 0.15)
				)
				(justify left bottom)
			)
		)
		(fp_text user "Author: Antmicro"
			(at -1.44 5.001 270)
			(layer "F.Fab")
			(effects
				(font
					(size 0.7 0.7)
					(thickness 0.15)
				)
				(justify left bottom)
			)
		)
		(pad "1" smd roundrect
			(at -1.1 0 270)
			(size 1.2 1.3)
			(layers "F.Cu" "F.Mask" "F.Paste")
			(roundrect_rratio 0.25)
			(net 399 "Net-(D4-A)")
			(pintype "passive")
		)
		(pad "2" smd roundrect
			(at 1.1 0 270)
			(size 1.2 1.3)
			(layers "F.Cu" "F.Mask" "F.Paste")
			(roundrect_rratio 0.25)
			(net 57 "+3V3_TB")
			(pintype "passive")
		)
	)
	(footprint "antmicro-footprints:R_0402_1005Metric"
		(layer "F.Cu")
		(at 159.249997 110.149999 180)
		(descr "Resistor SMD 0402")
		(tags "resistor SMD 0402")
		(property "Reference" "R104"
			(at -12.950004 -17.25 180)
			(layer "F.SilkS")
			(effects
				(font
					(size 0.7 0.7)
					(thickness 0.15)
				)
			)
		)
		(property "Value" "R_20k_0402"
			(at -1.011843 1.772047 180)
			(layer "F.Fab")
			(effects
				(font
					(size 0.7 0.7)
					(thickness 0.15)
				)
				(justify left bottom)
			)
		)
		(property "Datasheet" "https://www.bourns.com/docs/product-datasheets/cr.pdf"
			(at 0 0 180)
			(layer "F.Fab")
			(hide yes)
			(effects
				(font
					(size 1.27 1.27)
					(thickness 0.15)
				)
			)
		)
		(property "Description" "SMD Chip Resistor, 20 kohm, ± 1%, 62.5 mW, 0402 [1005 Metric], Thick Film, General Purpose"
			(at 0 0 180)
			(layer "F.Fab")
			(hide yes)
			(effects
				(font
					(size 1.27 1.27)
					(thickness 0.15)
				)
			)
		)
		(property "MPN" "CR0402-FX-2002GLF"
			(at 0 0 180)
			(unlocked yes)
			(layer "F.Fab")
			(hide yes)
			(effects
				(font
					(size 1 1)
					(thickness 0.15)
				)
			)
		)
		(property "Manufacturer" "Bourns"
			(at 0 0 180)
			(unlocked yes)
			(layer "F.Fab")
			(hide yes)
			(effects
				(font
					(size 1 1)
					(thickness 0.15)
				)
			)
		)
		(property "License" "Apache-2.0"
			(at 0 0 180)
			(unlocked yes)
			(layer "F.Fab")
			(hide yes)
			(effects
				(font
					(size 1 1)
					(thickness 0.15)
				)
			)
		)
		(property "Author" "Antmicro"
			(at 0 0 180)
			(unlocked yes)
			(layer "F.Fab")
			(hide yes)
			(effects
				(font
					(size 1 1)
					(thickness 0.15)
				)
			)
		)
		(property "Val" "20k"
			(at 0 0 180)
			(unlocked yes)
			(layer "F.Fab")
			(hide yes)
			(effects
				(font
					(size 1 1)
					(thickness 0.15)
				)
			)
		)
		(property "Tolerance" "1%"
			(at 0 0 180)
			(unlocked yes)
			(layer "F.Fab")
			(hide yes)
			(effects
				(font
					(size 1 1)
					(thickness 0.15)
				)
			)
		)
		(sheetname "/X710 DCDC converters/")
		(sheetfile "DCDC_converters_X710.kicad_sch")
		(attr smd)
		(fp_rect
			(start -0.925 -0.47)
			(end 0.925 0.47)
			(stroke
				(width 0.05)
				(type default)
			)
			(fill no)
			(layer "F.CrtYd")
		)
		(fp_rect
			(start -0.5 -0.25)
			(end 0.5 0.25)
			(stroke
				(width 0.15)
				(type solid)
			)
			(fill no)
			(layer "F.Fab")
		)
		(fp_text user "${REFERENCE}"
			(at -0.95 3.168 180)
			(layer "F.Fab")
			(effects
				(font
					(size 0.7 0.7)
					(thickness 0.15)
				)
				(justify left bottom)
			)
		)
		(fp_text user "Author: Antmicro"
			(at -0.95 4.169 180)
			(layer "F.Fab")
			(effects
				(font
					(size 0.7 0.7)
					(thickness 0.15)
				)
				(justify left bottom)
			)
		)
		(fp_text user "License: Apache-2.0"
			(at -0.95 5.169 180)
			(layer "F.Fab")
			(effects
				(font
					(size 0.7 0.7)
					(thickness 0.15)
				)
				(justify left bottom)
			)
		)
		(pad "1" smd roundrect
			(at -0.48 0 180)
			(size 0.59 0.64)
			(layers "F.Cu" "F.Mask" "F.Paste")
			(roundrect_rratio 0.25)
			(net 340 "/X710 DCDC converters/1V0_FB")
			(pintype "passive")
		)
		(pad "2" smd roundrect
			(at 0.48 0 180)
			(size 0.59 0.64)
			(layers "F.Cu" "F.Mask" "F.Paste")
			(roundrect_rratio 0.25)
			(net 339 "/X710 DCDC converters/+1V0_OUT")
			(pintype "passive")
		)
	)
	(footprint "antmicro-footprints:C_0603_1608Metric_EIA"
		(layer "F.Cu")
		(at 150.500001 105.600001 90)
		(descr "Capacitor SMD 0603, IPC-7351 Density Level A")
		(tags "Capacitor 0603")
		(property "Reference" "C136"
			(at -17.849995 14.449998 90)
			(layer "F.SilkS")
			(effects
				(font
					(size 0.7 0.7)
					(thickness 0.15)
				)
			)
		)
		(property "Value" "C_22u_16V_0603"
			(at -1.42757 1.770288 90)
			(layer "F.Fab")
			(effects
				(font
					(size 0.7 0.7)
					(thickness 0.15)
				)
				(justify left bottom)
			)
		)
		(property "Datasheet" "https://product.samsungsem.com/mlcc/CL10A226MO7JZN.do"
			(at 0 0 90)
			(layer "F.Fab")
			(hide yes)
			(effects
				(font
					(size 1.27 1.27)
					(thickness 0.15)
				)
			)
		)
		(property "Description" "SMD Multilayer Ceramic Capacitor"
			(at 0 0 90)
			(layer "F.Fab")
			(hide yes)
			(effects
				(font
					(size 1.27 1.27)
					(thickness 0.15)
				)
			)
		)
		(property "MPN" "CL10A226MO7JZNC"
			(at 0 0 90)
			(unlocked yes)
			(layer "F.Fab")
			(hide yes)
			(effects
				(font
					(size 1 1)
					(thickness 0.15)
				)
			)
		)
		(property "Manufacturer" "Samsung Electro-Mechanics"
			(at 0 0 90)
			(unlocked yes)
			(layer "F.Fab")
			(hide yes)
			(effects
				(font
					(size 1 1)
					(thickness 0.15)
				)
			)
		)
		(property "License" "Apache-2.0"
			(at 0 0 90)
			(unlocked yes)
			(layer "F.Fab")
			(hide yes)
			(effects
				(font
					(size 1 1)
					(thickness 0.15)
				)
			)
		)
		(property "Author" "Antmicro"
			(at 0 0 90)
			(unlocked yes)
			(layer "F.Fab")
			(hide yes)
			(effects
				(font
					(size 1 1)
					(thickness 0.15)
				)
			)
		)
		(property "Val" "22u"
			(at 0 0 90)
			(unlocked yes)
			(layer "F.Fab")
			(hide yes)
			(effects
				(font
					(size 1 1)
					(thickness 0.15)
				)
			)
		)
		(property "Voltage" "16V"
			(at 0 0 90)
			(unlocked yes)
			(layer "F.Fab")
			(hide yes)
			(effects
				(font
					(size 1 1)
					(thickness 0.15)
				)
			)
		)
		(property "Dielectric" ""
			(at 0 0 90)
			(unlocked yes)
			(layer "F.Fab")
			(hide yes)
			(effects
				(font
					(size 1 1)
					(thickness 0.15)
				)
			)
		)
		(sheetname "/X710 DCDC converters/")
		(sheetfile "DCDC_converters_X710.kicad_sch")
		(attr smd)
		(fp_line
			(start -0.15 -0.55)
			(end 0.15 -0.55)
			(stroke
				(width 0.15)
				(type solid)
			)
			(layer "F.SilkS")
		)
		(fp_line
			(start -0.15 0.55)
			(end 0.15 0.55)
			(stroke
				(width 0.15)
				(type solid)
			)
			(layer "F.SilkS")
		)
		(fp_rect
			(start -1.25 -0.65)
			(end 1.25 0.65)
			(stroke
				(width 0.05)
				(type solid)
			)
			(fill no)
			(layer "F.CrtYd")
		)
		(fp_rect
			(start -0.8 -0.45)
			(end 0.8 0.45)
			(stroke
				(width 0.15)
				(type solid)
			)
			(fill no)
			(layer "F.Fab")
		)
		(fp_text user "Author: Antmicro"
			(at -1.682 4.894 90)
			(layer "F.Fab")
			(effects
				(font
					(size 0.7 0.7)
					(thickness 0.15)
				)
				(justify left bottom)
			)
		)
		(fp_text user "${REFERENCE}"
			(at -1.682 3.895 90)
			(layer "F.Fab")
			(effects
				(font
					(size 0.7 0.7)
					(thickness 0.15)
				)
				(justify left bottom)
			)
		)
		(fp_text user "License: Apache-2.0"
			(at -1.682 5.895 90)
			(layer "F.Fab")
			(effects
				(font
					(size 0.7 0.7)
					(thickness 0.15)
				)
				(justify left bottom)
			)
		)
		(pad "1" smd roundrect
			(at -0.7 0 90)
			(size 0.8 1.1)
			(layers "F.Cu" "F.Mask" "F.Paste")
			(roundrect_rratio 0.2)
			(net 23 "GND")
			(pintype "passive")
		)
		(pad "2" smd roundrect
			(at 0.7 0 90)
			(size 0.8 1.1)
			(layers "F.Cu" "F.Mask" "F.Paste")
			(roundrect_rratio 0.2)
			(net 338 "/X710 DCDC converters/+1V88_OUT")
			(pintype "passive")
		)
	)
	(footprint "antmicro-footprints:Mech_Lightpipe_Mentor_1271.1001"
		(layer "F.Cu")
		(at 130.45 147.813534 180)
		(descr "1x1  Horizontal Light Guide with transparent pipe")
		(tags "Horizontal, THT, MECHANICAL, MODULE")
		(property "Reference" "H4"
			(at 1.7 -3.386466 0)
			(unlocked yes)
			(layer "F.SilkS")
			(effects
				(font
					(size 0.7 0.7)
					(thickness 0.15)
				)
				(justify left bottom)
			)
		)
		(property "Value" "Lightpipe_Mentor_1271.1001"
			(at 0 9 180)
			(unlocked yes)
			(layer "F.Fab")
			(effects
				(font
					(size 0.7 0.7)
					(thickness 0.15)
				)
				(justify left bottom)
			)
		)
		(property "Datasheet" "https://www.mentor.de.com/productpdfs/ll/ll14-20.pdf"
			(at 0 0 180)
			(layer "F.Fab")
			(hide yes)
			(effects
				(font
					(size 1.27 1.27)
					(thickness 0.15)
				)
			)
		)
		(property "Description" "Light Pipe, 14.45 mm, 1 Pipe, Circular, PC Board, Transparent"
			(at 0 0 180)
			(layer "F.Fab")
			(hide yes)
			(effects
				(font
					(size 1.27 1.27)
					(thickness 0.15)
				)
			)
		)
		(property "MPN" "1271.1001"
			(at 0 0 180)
			(unlocked yes)
			(layer "F.Fab")
			(hide yes)
			(effects
				(font
					(size 1 1)
					(thickness 0.15)
				)
			)
		)
		(property "Manufacturer" "Mentor Worldwide"
			(at 0 0 180)
			(unlocked yes)
			(layer "F.Fab")
			(hide yes)
			(effects
				(font
					(size 1 1)
					(thickness 0.15)
				)
			)
		)
		(property "Author" "Antmicro"
			(at 0 0 180)
			(unlocked yes)
			(layer "F.Fab")
			(hide yes)
			(effects
				(font
					(size 1 1)
					(thickness 0.15)
				)
			)
		)
		(property "License" "Apache-2.0"
			(at 0 0 180)
			(unlocked yes)
			(layer "F.Fab")
			(hide yes)
			(effects
				(font
					(size 1 1)
					(thickness 0.15)
				)
			)
		)
		(sheetname "/")
		(sheetfile "thunderbolt-to-10gbe-adapter.kicad_sch")
		(attr through_hole)
		(fp_rect
			(start -1.55 -2.1)
			(end 1.55 1.3)
			(stroke
				(width 0.05)
				(type solid)
			)
			(fill no)
			(layer "F.SilkS")
		)
		(fp_rect
			(start -1.75 -2.3)
			(end 1.75 1.475)
			(stroke
				(width 0.05)
				(type solid)
			)
			(fill no)
			(layer "F.CrtYd")
		)
		(fp_rect
			(start -1.4732 -8.128)
			(end 1.4732 6.2484)
			(stroke
				(width 0.15)
				(type solid)
			)
			(fill no)
			(layer "F.Fab")
		)
		(fp_text user "${REFERENCE}"
			(at -1.8 12.9 180)
			(layer "F.Fab")
			(effects
				(font
					(size 0.7 0.7)
					(thickness 0.15)
				)
				(justify left bottom)
			)
		)
		(fp_text user "Author: Antmicro"
			(at -1.8 10.5 180)
			(layer "F.Fab")
			(effects
				(font
					(size 0.7 0.7)
					(thickness 0.15)
				)
				(justify left bottom)
			)
		)
		(fp_text user "License: Apache-2.0"
			(at -1.8 11.7 180)
			(layer "F.Fab")
			(effects
				(font
					(size 0.7 0.7)
					(thickness 0.15)
				)
				(justify left bottom)
			)
		)
		(pad "" np_thru_hole circle
			(at 0 0 180)
			(size 2.3 2.3)
			(drill 2.3)
			(layers "*.Cu" "*.Mask")
		)
	)
	(footprint "antmicro-footprints:C_0603_1608Metric"
		(layer "F.Cu")
		(at 149.305 95.374999 180)
		(descr "Capacitor SMD 0603")
		(tags "capacitor 0603")
		(property "Reference" "C169"
			(at -23.294999 -19.625001 180)
			(layer "F.SilkS")
			(effects
				(font
					(size 0.7 0.7)
					(thickness 0.15)
				)
			)
		)
		(property "Value" "C_10u_10V_X7R_0603"
			(at -1.42757 1.770288 180)
			(layer "F.Fab")
			(effects
				(font
					(size 0.7 0.7)
					(thickness 0.15)
				)
				(justify left bottom)
			)
		)
		(property "Datasheet" "https://www.murata.com/products/productdetail?partno=GRM188Z71A106KA73%23"
			(at 0 0 180)
			(layer "F.Fab")
			(hide yes)
			(effects
				(font
					(size 1.27 1.27)
					(thickness 0.15)
				)
			)
		)
		(property "Description" "SMD Multilayer Ceramic Capacitor,  10µF, 10V, 0603, ±10%, X7R"
			(at 0 0 180)
			(layer "F.Fab")
			(hide yes)
			(effects
				(font
					(size 1.27 1.27)
					(thickness 0.15)
				)
			)
		)
		(property "MPN" "GRM188Z71A106KA73D"
			(at 0 0 180)
			(unlocked yes)
			(layer "F.Fab")
			(hide yes)
			(effects
				(font
					(size 1 1)
					(thickness 0.15)
				)
			)
		)
		(property "Val" "10u"
			(at 0 0 180)
			(unlocked yes)
			(layer "F.Fab")
			(hide yes)
			(effects
				(font
					(size 1 1)
					(thickness 0.15)
				)
			)
		)
		(property "Voltage" "10V"
			(at 0 0 180)
			(unlocked yes)
			(layer "F.Fab")
			(hide yes)
			(effects
				(font
					(size 1 1)
					(thickness 0.15)
				)
			)
		)
		(property "Dielectric" "X7R"
			(at 0 0 180)
			(unlocked yes)
			(layer "F.Fab")
			(hide yes)
			(effects
				(font
					(size 1 1)
					(thickness 0.15)
				)
			)
		)
		(property "Manufacturer" "Murata"
			(at 0 0 180)
			(unlocked yes)
			(layer "F.Fab")
			(hide yes)
			(effects
				(font
					(size 1 1)
					(thickness 0.15)
				)
			)
		)
		(property "License" "Apache-2.0"
			(at 0 0 180)
			(unlocked yes)
			(layer "F.Fab")
			(hide yes)
			(effects
				(font
					(size 1 1)
					(thickness 0.15)
				)
			)
		)
		(property "Author" "Antmicro"
			(at 0 0 180)
			(unlocked yes)
			(layer "F.Fab")
			(hide yes)
			(effects
				(font
					(size 1 1)
					(thickness 0.15)
				)
			)
		)
		(sheetname "/X710-AT2 power/")
		(sheetfile "x710-at2-power.kicad_sch")
		(attr smd)
		(fp_line
			(start -0.15 0.4)
			(end 0.15 0.4)
			(stroke
				(width 0.15)
				(type solid)
			)
			(layer "F.SilkS")
		)
		(fp_line
			(start -0.15 -0.4)
			(end 0.15 -0.4)
			(stroke
				(width 0.15)
				(type solid)
			)
			(layer "F.SilkS")
		)
		(fp_rect
			(start -1.25 -0.65)
			(end 1.25 0.65)
			(stroke
				(width 0.05)
				(type solid)
			)
			(fill no)
			(layer "F.CrtYd")
		)
		(fp_rect
			(start -0.8 -0.4)
			(end 0.8 0.4)
			(stroke
				(width 0.15)
				(type solid)
			)
			(fill no)
			(layer "F.Fab")
		)
		(fp_text user "${REFERENCE}"
			(at -1.682 3.895 180)
			(layer "F.Fab")
			(effects
				(font
					(size 0.7 0.7)
					(thickness 0.15)
				)
				(justify left bottom)
			)
		)
		(fp_text user "Author: Antmicro"
			(at -1.682 4.894 180)
			(layer "F.Fab")
			(effects
				(font
					(size 0.7 0.7)
					(thickness 0.15)
				)
				(justify left bottom)
			)
		)
		(fp_text user "License: Apache-2.0"
			(at -1.682 5.895 180)
			(layer "F.Fab")
			(effects
				(font
					(size 0.7 0.7)
					(thickness 0.15)
				)
				(justify left bottom)
			)
		)
		(pad "1" smd roundrect
			(at -0.7 0 180)
			(size 0.8 1)
			(layers "F.Cu" "F.Mask" "F.Paste")
			(roundrect_rratio 0.2)
			(net 23 "GND")
			(pintype "passive")
		)
		(pad "2" smd roundrect
			(at 0.7 0 180)
			(size 0.8 1)
			(layers "F.Cu" "F.Mask" "F.Paste")
			(roundrect_rratio 0.2)
			(net 10 "AVDDH")
			(pintype "passive")
		)
	)
)
